(kicad_pcb
	(version 20260206)
	(generator "pcbnew")
	(generator_version "10.0")
	(general
		(thickness 1.6)
		(legacy_teardrops no)
	)
	(paper "A4")
	(title_block
		(title "04192023_DAF0TMB3IC0_F0TG_MB_C_brd_V02_OCP.brd")
		(comment 1 "Grand Teton / footprints 1181-1187 of 8354")
	)
	(layers
		(0 "F.Cu" signal "TOP")
		(4 "In1.Cu" signal "GND")
		(6 "In2.Cu" signal "IN1")
		(8 "In3.Cu" signal "GND1")
		(10 "In4.Cu" signal "IN2")
		(12 "In5.Cu" signal "GND2")
		(14 "In6.Cu" signal "IN3")
		(16 "In7.Cu" signal "GND3")
		(18 "In8.Cu" signal "VCC")
		(20 "In9.Cu" signal "VCC1")
		(22 "In10.Cu" signal "GND4")
		(24 "In11.Cu" signal "IN4")
		(26 "In12.Cu" signal "GND5")
		(28 "In13.Cu" signal "IN5")
		(30 "In14.Cu" signal "GND6")
		(32 "In15.Cu" signal "IN6")
		(34 "In16.Cu" signal "GND7")
		(2 "B.Cu" signal "BOTTOM")
		(9 "F.Adhes" user "F.Adhesive")
		(11 "B.Adhes" user "B.Adhesive")
		(13 "F.Paste" user "Package Geometry/Pastemask Top")
		(15 "B.Paste" user "Package Geometry/Pastemask Bottom")
		(5 "F.SilkS" user "Ref Des/Silkscreen Top")
		(7 "B.SilkS" user "Ref Des/Silkscreen Bottom")
		(1 "F.Mask" user "Board Geometry/Soldermask Top")
		(3 "B.Mask" user "Board Geometry/Soldermask Bottom")
		(17 "Dwgs.User" user "User.Drawings")
		(19 "Cmts.User" user "User.Comments")
		(21 "Eco1.User" user "User.Eco1")
		(23 "Eco2.User" user "User.Eco2")
		(25 "Edge.Cuts" user "Board Geometry/Outline")
		(27 "Margin" user)
		(31 "F.CrtYd" user "Package Geometry/Place Bound Top")
		(29 "B.CrtYd" user "Package Geometry/Place Bound Bottom")
		(35 "F.Fab" user "Ref Des/Assembly Top")
		(33 "B.Fab" user "Ref Des/Assembly Bottom")
	)
	(footprint ""
		(layer "F.Cu")
		(at 111.076486 -171.812458 90)
		(property "Reference" "PC325_1"
			(at 0 0 90)
			(layer "F.SilkS")
			(hide yes)
			(effects
				(font
					(size 1.27 1.27)
				)
			)
		)
		(property "Value" ""
			(at 0 0 90)
			(layer "F.Fab")
			(effects
				(font
					(size 1.27 1.27)
				)
			)
		)
		(duplicate_pad_numbers_are_jumpers no)
		(fp_line
			(start 0.7874 -0.4064)
			(end 0.7874 0.4064)
			(stroke
				(width 0.1524)
				(type default)
			)
			(layer "F.SilkS")
		)
		(fp_line
			(start -0.7874 -0.4064)
			(end 0.7874 -0.4064)
			(stroke
				(width 0.1524)
				(type default)
			)
			(layer "F.SilkS")
		)
		(fp_line
			(start 0.7874 0.4064)
			(end -0.7874 0.4064)
			(stroke
				(width 0.1524)
				(type default)
			)
			(layer "F.SilkS")
		)
		(fp_line
			(start -0.7874 0.4064)
			(end -0.7874 -0.4064)
			(stroke
				(width 0.1524)
				(type default)
			)
			(layer "F.SilkS")
		)
		(fp_line
			(start -0.12065 -0.305054)
			(end -0.12065 -0.2794)
			(stroke
				(width 0.1)
				(type default)
			)
			(layer "F.Fab")
		)
		(fp_line
			(start -0.67945 -0.305054)
			(end -0.12065 -0.305054)
			(stroke
				(width 0.1)
				(type default)
			)
			(layer "F.Fab")
		)
		(fp_line
			(start 0.67945 -0.3048)
			(end 0.67945 0.3048)
			(stroke
				(width 0.1)
				(type default)
			)
			(layer "F.Fab")
		)
		(fp_line
			(start 0.12065 -0.3048)
			(end 0.67945 -0.3048)
			(stroke
				(width 0.1)
				(type default)
			)
			(layer "F.Fab")
		)
		(fp_line
			(start 0.12065 -0.2794)
			(end 0.12065 -0.3048)
			(stroke
				(width 0.1)
				(type default)
			)
			(layer "F.Fab")
		)
		(fp_line
			(start -0.12065 -0.2794)
			(end 0.12065 -0.2794)
			(stroke
				(width 0.1)
				(type default)
			)
			(layer "F.Fab")
		)
		(fp_line
			(start 0.120396 0.2794)
			(end -0.12065 0.2794)
			(stroke
				(width 0.1)
				(type default)
			)
			(layer "F.Fab")
		)
		(fp_line
			(start -0.12065 0.2794)
			(end -0.12065 0.3048)
			(stroke
				(width 0.1)
				(type default)
			)
			(layer "F.Fab")
		)
		(fp_line
			(start 0.67945 0.3048)
			(end 0.120396 0.3048)
			(stroke
				(width 0.1)
				(type default)
			)
			(layer "F.Fab")
		)
		(fp_line
			(start 0.120396 0.3048)
			(end 0.120396 0.2794)
			(stroke
				(width 0.1)
				(type default)
			)
			(layer "F.Fab")
		)
		(fp_line
			(start -0.12065 0.3048)
			(end -0.67945 0.3048)
			(stroke
				(width 0.1)
				(type default)
			)
			(layer "F.Fab")
		)
		(fp_line
			(start -0.67945 0.3048)
			(end -0.67945 -0.305054)
			(stroke
				(width 0.1)
				(type default)
			)
			(layer "F.Fab")
		)
		(pad "1" smd circle
			(at -0.40005 0 90)
			(size 0 0)
			(layers "F.Cu" "F.Mask" "F.Paste")
			(net "SW_P12V_AUX_PVDDCR_SOC_P1_FLT")
		)
		(pad "2" smd circle
			(at 0.40005 0 90)
			(size 0 0)
			(layers "F.Cu" "F.Mask" "F.Paste")
			(net "GND")
		)
	)
	(footprint ""
		(layer "F.Cu")
		(at 329.360022 -33.969706)
		(property "Reference" "C2045"
			(at 0 0 0)
			(layer "F.SilkS")
			(hide yes)
			(effects
				(font
					(size 1.27 1.27)
				)
			)
		)
		(property "Value" ""
			(at 0 0 0)
			(layer "F.Fab")
			(effects
				(font
					(size 1.27 1.27)
				)
			)
		)
		(duplicate_pad_numbers_are_jumpers no)
		(fp_line
			(start -0.7874 -0.4064)
			(end 0.7874 -0.4064)
			(stroke
				(width 0.1524)
				(type default)
			)
			(layer "F.SilkS")
		)
		(fp_line
			(start -0.7874 0.4064)
			(end -0.7874 -0.4064)
			(stroke
				(width 0.1524)
				(type default)
			)
			(layer "F.SilkS")
		)
		(fp_line
			(start 0.7874 -0.4064)
			(end 0.7874 0.4064)
			(stroke
				(width 0.1524)
				(type default)
			)
			(layer "F.SilkS")
		)
		(fp_line
			(start 0.7874 0.4064)
			(end -0.7874 0.4064)
			(stroke
				(width 0.1524)
				(type default)
			)
			(layer "F.SilkS")
		)
		(fp_line
			(start -0.67945 -0.305054)
			(end -0.12065 -0.305054)
			(stroke
				(width 0.1)
				(type default)
			)
			(layer "F.Fab")
		)
		(fp_line
			(start -0.67945 0.3048)
			(end -0.67945 -0.305054)
			(stroke
				(width 0.1)
				(type default)
			)
			(layer "F.Fab")
		)
		(fp_line
			(start -0.12065 -0.305054)
			(end -0.12065 -0.2794)
			(stroke
				(width 0.1)
				(type default)
			)
			(layer "F.Fab")
		)
		(fp_line
			(start -0.12065 -0.2794)
			(end 0.12065 -0.2794)
			(stroke
				(width 0.1)
				(type default)
			)
			(layer "F.Fab")
		)
		(fp_line
			(start -0.12065 0.2794)
			(end -0.12065 0.3048)
			(stroke
				(width 0.1)
				(type default)
			)
			(layer "F.Fab")
		)
		(fp_line
			(start -0.12065 0.3048)
			(end -0.67945 0.3048)
			(stroke
				(width 0.1)
				(type default)
			)
			(layer "F.Fab")
		)
		(fp_line
			(start 0.120396 0.2794)
			(end -0.12065 0.2794)
			(stroke
				(width 0.1)
				(type default)
			)
			(layer "F.Fab")
		)
		(fp_line
			(start 0.120396 0.3048)
			(end 0.120396 0.2794)
			(stroke
				(width 0.1)
				(type default)
			)
			(layer "F.Fab")
		)
		(fp_line
			(start 0.12065 -0.3048)
			(end 0.67945 -0.3048)
			(stroke
				(width 0.1)
				(type default)
			)
			(layer "F.Fab")
		)
		(fp_line
			(start 0.12065 -0.2794)
			(end 0.12065 -0.3048)
			(stroke
				(width 0.1)
				(type default)
			)
			(layer "F.Fab")
		)
		(fp_line
			(start 0.67945 -0.3048)
			(end 0.67945 0.3048)
			(stroke
				(width 0.1)
				(type default)
			)
			(layer "F.Fab")
		)
		(fp_line
			(start 0.67945 0.3048)
			(end 0.120396 0.3048)
			(stroke
				(width 0.1)
				(type default)
			)
			(layer "F.Fab")
		)
		(pad "1" smd circle
			(at -0.40005 0)
			(size 0 0)
			(layers "F.Cu" "F.Mask" "F.Paste")
			(net "P3V3_PDB_AUX_ADC_MAM")
		)
		(pad "2" smd circle
			(at 0.40005 0)
			(size 0 0)
			(layers "F.Cu" "F.Mask" "F.Paste")
			(net "GND")
		)
	)
	(footprint ""
		(layer "F.Cu")
		(at 344.149426 -339.676232 90)
		(property "Reference" "PR95"
			(at 0 0 90)
			(layer "F.SilkS")
			(hide yes)
			(effects
				(font
					(size 1.27 1.27)
				)
			)
		)
		(property "Value" ""
			(at 0 0 90)
			(layer "F.Fab")
			(effects
				(font
					(size 1.27 1.27)
				)
			)
		)
		(duplicate_pad_numbers_are_jumpers no)
		(fp_line
			(start 0.7874 -0.4064)
			(end 0.7874 0.4064)
			(stroke
				(width 0.1524)
				(type default)
			)
			(layer "F.SilkS")
		)
		(fp_line
			(start -0.7874 -0.4064)
			(end 0.7874 -0.4064)
			(stroke
				(width 0.1524)
				(type default)
			)
			(layer "F.SilkS")
		)
		(fp_line
			(start 0.7874 0.4064)
			(end -0.7874 0.4064)
			(stroke
				(width 0.1524)
				(type default)
			)
			(layer "F.SilkS")
		)
		(fp_line
			(start -0.7874 0.4064)
			(end -0.7874 -0.4064)
			(stroke
				(width 0.1524)
				(type default)
			)
			(layer "F.SilkS")
		)
		(fp_line
			(start -0.12065 -0.305054)
			(end -0.12065 -0.2794)
			(stroke
				(width 0.1)
				(type default)
			)
			(layer "F.Fab")
		)
		(fp_line
			(start -0.67945 -0.305054)
			(end -0.12065 -0.305054)
			(stroke
				(width 0.1)
				(type default)
			)
			(layer "F.Fab")
		)
		(fp_line
			(start 0.67945 -0.3048)
			(end 0.67945 0.3048)
			(stroke
				(width 0.1)
				(type default)
			)
			(layer "F.Fab")
		)
		(fp_line
			(start 0.12065 -0.3048)
			(end 0.67945 -0.3048)
			(stroke
				(width 0.1)
				(type default)
			)
			(layer "F.Fab")
		)
		(fp_line
			(start 0.12065 -0.2794)
			(end 0.12065 -0.3048)
			(stroke
				(width 0.1)
				(type default)
			)
			(layer "F.Fab")
		)
		(fp_line
			(start -0.12065 -0.2794)
			(end 0.12065 -0.2794)
			(stroke
				(width 0.1)
				(type default)
			)
			(layer "F.Fab")
		)
		(fp_line
			(start 0.120396 0.2794)
			(end -0.12065 0.2794)
			(stroke
				(width 0.1)
				(type default)
			)
			(layer "F.Fab")
		)
		(fp_line
			(start -0.12065 0.2794)
			(end -0.12065 0.3048)
			(stroke
				(width 0.1)
				(type default)
			)
			(layer "F.Fab")
		)
		(fp_line
			(start 0.67945 0.3048)
			(end 0.120396 0.3048)
			(stroke
				(width 0.1)
				(type default)
			)
			(layer "F.Fab")
		)
		(fp_line
			(start 0.120396 0.3048)
			(end 0.120396 0.2794)
			(stroke
				(width 0.1)
				(type default)
			)
			(layer "F.Fab")
		)
		(fp_line
			(start -0.12065 0.3048)
			(end -0.67945 0.3048)
			(stroke
				(width 0.1)
				(type default)
			)
			(layer "F.Fab")
		)
		(fp_line
			(start -0.67945 0.3048)
			(end -0.67945 -0.305054)
			(stroke
				(width 0.1)
				(type default)
			)
			(layer "F.Fab")
		)
		(pad "1" smd circle
			(at -0.40005 0 90)
			(size 0 0)
			(layers "F.Cu" "F.Mask" "F.Paste")
			(net "SW_PVDDCR_CPU1_P0_BOOT5")
		)
		(pad "2" smd circle
			(at 0.40005 0 90)
			(size 0 0)
			(layers "F.Cu" "F.Mask" "F.Paste")
			(net "SW_PVDDCR_CPU1_P0_BOOT5_R")
		)
	)
	(footprint ""
		(layer "F.Cu")
		(at 210.086956 -30.276292 90)
		(property "Reference" "R3622"
			(at 0 0 90)
			(layer "F.SilkS")
			(hide yes)
			(effects
				(font
					(size 1.27 1.27)
				)
			)
		)
		(property "Value" ""
			(at 0 0 90)
			(layer "F.Fab")
			(effects
				(font
					(size 1.27 1.27)
				)
			)
		)
		(duplicate_pad_numbers_are_jumpers no)
		(fp_line
			(start 0.7874 -0.4064)
			(end 0.7874 0.4064)
			(stroke
				(width 0.1524)
				(type default)
			)
			(layer "F.SilkS")
		)
		(fp_line
			(start -0.7874 -0.4064)
			(end 0.7874 -0.4064)
			(stroke
				(width 0.1524)
				(type default)
			)
			(layer "F.SilkS")
		)
		(fp_line
			(start 0.7874 0.4064)
			(end -0.7874 0.4064)
			(stroke
				(width 0.1524)
				(type default)
			)
			(layer "F.SilkS")
		)
		(fp_line
			(start -0.7874 0.4064)
			(end -0.7874 -0.4064)
			(stroke
				(width 0.1524)
				(type default)
			)
			(layer "F.SilkS")
		)
		(fp_line
			(start -0.12065 -0.305054)
			(end -0.12065 -0.2794)
			(stroke
				(width 0.1)
				(type default)
			)
			(layer "F.Fab")
		)
		(fp_line
			(start -0.67945 -0.305054)
			(end -0.12065 -0.305054)
			(stroke
				(width 0.1)
				(type default)
			)
			(layer "F.Fab")
		)
		(fp_line
			(start 0.67945 -0.3048)
			(end 0.67945 0.3048)
			(stroke
				(width 0.1)
				(type default)
			)
			(layer "F.Fab")
		)
		(fp_line
			(start 0.12065 -0.3048)
			(end 0.67945 -0.3048)
			(stroke
				(width 0.1)
				(type default)
			)
			(layer "F.Fab")
		)
		(fp_line
			(start 0.12065 -0.2794)
			(end 0.12065 -0.3048)
			(stroke
				(width 0.1)
				(type default)
			)
			(layer "F.Fab")
		)
		(fp_line
			(start -0.12065 -0.2794)
			(end 0.12065 -0.2794)
			(stroke
				(width 0.1)
				(type default)
			)
			(layer "F.Fab")
		)
		(fp_line
			(start 0.120396 0.2794)
			(end -0.12065 0.2794)
			(stroke
				(width 0.1)
				(type default)
			)
			(layer "F.Fab")
		)
		(fp_line
			(start -0.12065 0.2794)
			(end -0.12065 0.3048)
			(stroke
				(width 0.1)
				(type default)
			)
			(layer "F.Fab")
		)
		(fp_line
			(start 0.67945 0.3048)
			(end 0.120396 0.3048)
			(stroke
				(width 0.1)
				(type default)
			)
			(layer "F.Fab")
		)
		(fp_line
			(start 0.120396 0.3048)
			(end 0.120396 0.2794)
			(stroke
				(width 0.1)
				(type default)
			)
			(layer "F.Fab")
		)
		(fp_line
			(start -0.12065 0.3048)
			(end -0.67945 0.3048)
			(stroke
				(width 0.1)
				(type default)
			)
			(layer "F.Fab")
		)
		(fp_line
			(start -0.67945 0.3048)
			(end -0.67945 -0.305054)
			(stroke
				(width 0.1)
				(type default)
			)
			(layer "F.Fab")
		)
		(pad "1" smd circle
			(at -0.40005 0 90)
			(size 0 0)
			(layers "F.Cu" "F.Mask" "F.Paste")
			(net "P3V3_AUX")
		)
		(pad "2" smd circle
			(at 0.40005 0 90)
			(size 0 0)
			(layers "F.Cu" "F.Mask" "F.Paste")
			(net "INA230_5_A0")
		)
	)
	(footprint ""
		(layer "F.Cu")
		(at 294.421052 -115.237514)
		(property "Reference" "R2703"
			(at 0 0 0)
			(layer "F.SilkS")
			(hide yes)
			(effects
				(font
					(size 1.27 1.27)
				)
			)
		)
		(property "Value" ""
			(at 0 0 0)
			(layer "F.Fab")
			(effects
				(font
					(size 1.27 1.27)
				)
			)
		)
		(duplicate_pad_numbers_are_jumpers no)
		(fp_line
			(start -0.7874 -0.4064)
			(end 0.7874 -0.4064)
			(stroke
				(width 0.1524)
				(type default)
			)
			(layer "F.SilkS")
		)
		(fp_line
			(start -0.7874 0.4064)
			(end -0.7874 -0.4064)
			(stroke
				(width 0.1524)
				(type default)
			)
			(layer "F.SilkS")
		)
		(fp_line
			(start 0.7874 -0.4064)
			(end 0.7874 0.4064)
			(stroke
				(width 0.1524)
				(type default)
			)
			(layer "F.SilkS")
		)
		(fp_line
			(start 0.7874 0.4064)
			(end -0.7874 0.4064)
			(stroke
				(width 0.1524)
				(type default)
			)
			(layer "F.SilkS")
		)
		(fp_line
			(start -0.67945 -0.305054)
			(end -0.12065 -0.305054)
			(stroke
				(width 0.1)
				(type default)
			)
			(layer "F.Fab")
		)
		(fp_line
			(start -0.67945 0.3048)
			(end -0.67945 -0.305054)
			(stroke
				(width 0.1)
				(type default)
			)
			(layer "F.Fab")
		)
		(fp_line
			(start -0.12065 -0.305054)
			(end -0.12065 -0.2794)
			(stroke
				(width 0.1)
				(type default)
			)
			(layer "F.Fab")
		)
		(fp_line
			(start -0.12065 -0.2794)
			(end 0.12065 -0.2794)
			(stroke
				(width 0.1)
				(type default)
			)
			(layer "F.Fab")
		)
		(fp_line
			(start -0.12065 0.2794)
			(end -0.12065 0.3048)
			(stroke
				(width 0.1)
				(type default)
			)
			(layer "F.Fab")
		)
		(fp_line
			(start -0.12065 0.3048)
			(end -0.67945 0.3048)
			(stroke
				(width 0.1)
				(type default)
			)
			(layer "F.Fab")
		)
		(fp_line
			(start 0.120396 0.2794)
			(end -0.12065 0.2794)
			(stroke
				(width 0.1)
				(type default)
			)
			(layer "F.Fab")
		)
		(fp_line
			(start 0.120396 0.3048)
			(end 0.120396 0.2794)
			(stroke
				(width 0.1)
				(type default)
			)
			(layer "F.Fab")
		)
		(fp_line
			(start 0.12065 -0.3048)
			(end 0.67945 -0.3048)
			(stroke
				(width 0.1)
				(type default)
			)
			(layer "F.Fab")
		)
		(fp_line
			(start 0.12065 -0.2794)
			(end 0.12065 -0.3048)
			(stroke
				(width 0.1)
				(type default)
			)
			(layer "F.Fab")
		)
		(fp_line
			(start 0.67945 -0.3048)
			(end 0.67945 0.3048)
			(stroke
				(width 0.1)
				(type default)
			)
			(layer "F.Fab")
		)
		(fp_line
			(start 0.67945 0.3048)
			(end 0.120396 0.3048)
			(stroke
				(width 0.1)
				(type default)
			)
			(layer "F.Fab")
		)
		(pad "1" smd circle
			(at -0.40005 0)
			(size 0 0)
			(layers "F.Cu" "F.Mask" "F.Paste")
			(net "SMB_BMC_SWB_SCL_R4")
		)
		(pad "2" smd circle
			(at 0.40005 0)
			(size 0 0)
			(layers "F.Cu" "F.Mask" "F.Paste")
			(net "SMB_BMC_SWB_SCL")
		)
	)
	(footprint ""
		(layer "F.Cu")
		(at 370.767102 -414.636458 -90)
		(property "Reference" "C6566"
			(at 0 0 270)
			(layer "F.SilkS")
			(hide yes)
			(effects
				(font
					(size 1.27 1.27)
				)
			)
		)
		(property "Value" ""
			(at 0 0 270)
			(layer "F.Fab")
			(effects
				(font
					(size 1.27 1.27)
				)
			)
		)
		(duplicate_pad_numbers_are_jumpers no)
		(fp_line
			(start -0.299974 0.150114)
			(end -0.299974 -0.150114)
			(stroke
				(width 0.1)
				(type default)
			)
			(layer "F.Fab")
		)
		(fp_line
			(start 0.299974 0.150114)
			(end -0.299974 0.150114)
			(stroke
				(width 0.1)
				(type default)
			)
			(layer "F.Fab")
		)
		(fp_line
			(start -0.299974 -0.150114)
			(end 0.299974 -0.150114)
			(stroke
				(width 0.1)
				(type default)
			)
			(layer "F.Fab")
		)
		(fp_line
			(start 0.299974 -0.150114)
			(end 0.299974 0.150114)
			(stroke
				(width 0.1)
				(type default)
			)
			(layer "F.Fab")
		)
		(pad "1" smd rect
			(at -0.2667 0 270)
			(size 0.3048 0.381)
			(layers "F.Cu" "F.Mask" "F.Paste")
			(net "P5E_CPU0_P2_TX_BUF_C_DN<0>")
		)
		(pad "2" smd rect
			(at 0.2667 0 270)
			(size 0.3048 0.381)
			(layers "F.Cu" "F.Mask" "F.Paste")
			(net "P5E_CPU0_P2_TX_BUF_DN<0>")
		)
	)
	(footprint ""
		(layer "F.Cu")
		(at 23.890478 -17.623536 90)
		(property "Reference" "C684"
			(at 0 0 90)
			(layer "F.SilkS")
			(hide yes)
			(effects
				(font
					(size 1.27 1.27)
				)
			)
		)
		(property "Value" ""
			(at 0 0 90)
			(layer "F.Fab")
			(effects
				(font
					(size 1.27 1.27)
				)
			)
		)
		(duplicate_pad_numbers_are_jumpers no)
		(fp_line
			(start 0.299974 -0.150114)
			(end 0.299974 0.150114)
			(stroke
				(width 0.1)
				(type default)
			)
			(layer "F.Fab")
		)
		(fp_line
			(start -0.299974 -0.150114)
			(end 0.299974 -0.150114)
			(stroke
				(width 0.1)
				(type default)
			)
			(layer "F.Fab")
		)
		(fp_line
			(start 0.299974 0.150114)
			(end -0.299974 0.150114)
			(stroke
				(width 0.1)
				(type default)
			)
			(layer "F.Fab")
		)
		(fp_line
			(start -0.299974 0.150114)
			(end -0.299974 -0.150114)
			(stroke
				(width 0.1)
				(type default)
			)
			(layer "F.Fab")
		)
		(pad "1" smd rect
			(at -0.2667 0 90)
			(size 0.3048 0.381)
			(layers "F.Cu" "F.Mask" "F.Paste")
			(net "P5E_CPU1_G1_TX_C_DN<12>")
		)
		(pad "2" smd rect
			(at 0.2667 0 90)
			(size 0.3048 0.381)
			(layers "F.Cu" "F.Mask" "F.Paste")
			(net "P5E_CPU1_G1_TX_DN<12>")
		)
	)
)
